# BASEBOARD_FAB2 (Tioga Pass) — schematic netlist excerpt (pin names and nets, part order shuffled) for the footprints in the layout excerpt that follows; sources: Cadence DE-HDL packaged netlist, KiCad conversion of Wiwynn_Tioga_Pass_MB.brd

R3P60  RES  240 1.0% CHIP  pkg 0402  page 99 : A = PVCCIO_CPU0 ; B = SMB_DDR_DEF_SCL_G
CF17  SC22P50V2JN-4GP  5%  pkg SMD-BCG  page 218 : \1\ = VR_PVDDQ_DEF_AIREF1 ; \2\ = ISENSE_PVDDQ_DEF_PH1_IMON
R1T1  RES  10.0K 1% CHIP  pkg 0402  page 139 : A = RMII_BMC_PCH_SPRNGVLLE_CRSDV ; B = GND

(kicad_pcb
	(version 20260206)
	(generator "pcbnew")
	(generator_version "10.0")
	(general
		(thickness 1.6)
		(legacy_teardrops no)
	)
	(paper "A4")
	(title_block
		(title "Wiwynn_Tioga_Pass_MB.brd")
		(comment 1 "Tioga Pass / footprints 3096-3098 of 4770")
	)
	(layers
		(0 "F.Cu" signal "TOP")
		(4 "In1.Cu" signal "L2GND")
		(6 "In2.Cu" signal "L3")
		(8 "In3.Cu" signal "L4GND")
		(10 "In4.Cu" signal "L5")
		(12 "In5.Cu" signal "L6GND")
		(14 "In6.Cu" signal "L7VCC")
		(16 "In7.Cu" signal "L8VCC")
		(18 "In8.Cu" signal "L9GND")
		(20 "In9.Cu" signal "L10")
		(22 "In10.Cu" signal "L11GND")
		(24 "In11.Cu" signal "L12")
		(26 "In12.Cu" signal "L13GND")
		(2 "B.Cu" signal "BOTTOM")
		(9 "F.Adhes" user "F.Adhesive")
		(11 "B.Adhes" user "B.Adhesive")
		(13 "F.Paste" user "Package Geometry/Pastemask Top")
		(15 "B.Paste" user "Package Geometry/Pastemask Bottom")
		(5 "F.SilkS" user "Ref Des/Silkscreen Top")
		(7 "B.SilkS" user "Ref Des/Silkscreen Bottom")
		(1 "F.Mask" user "Board Geometry/Soldermask Top")
		(3 "B.Mask" user "Board Geometry/Soldermask Bottom")
		(17 "Dwgs.User" user "User.Drawings")
		(19 "Cmts.User" user "User.Comments")
		(21 "Eco1.User" user "User.Eco1")
		(23 "Eco2.User" user "User.Eco2")
		(25 "Edge.Cuts" user "Board Geometry/Outline")
		(27 "Margin" user)
		(31 "F.CrtYd" user "Package Geometry/Place Bound Top")
		(29 "B.CrtYd" user "Package Geometry/Place Bound Bottom")
		(35 "F.Fab" user "Ref Des/Assembly Top")
		(33 "B.Fab" user "Ref Des/Assembly Bottom")
	)
	(footprint ""
		(layer "B.Cu")
		(at 362.229654 -141.84249 -90)
		(property "Reference" "CF17"
			(at 0 0 90)
			(layer "B.SilkS")
			(hide yes)
			(effects
				(font
					(size 1.27 1.27)
				)
				(justify mirror)
			)
		)
		(property "Value" "*"
			(at -1.1811 -2.8194 270)
			(unlocked yes)
			(layer "B.Fab")
			(hide yes)
			(effects
				(font
					(size 1.27 1.016)
					(thickness 0.1524)
				)
				(justify mirror)
			)
		)
		(property "Device Type" "SC22P50V2JN-4GP_SMD-BCG-SC22P5A"
			(at -1.1811 -4.3434 270)
			(unlocked yes)
			(layer "B.Fab")
			(hide yes)
			(effects
				(font
					(size 1.27 1.016)
					(thickness 0.1524)
				)
				(justify mirror)
			)
		)
		(duplicate_pad_numbers_are_jumpers no)
		(fp_rect
			(start 0.4318 0.9525)
			(end -0.4318 -0.9525)
			(stroke
				(width 0)
				(type default)
			)
			(fill no)
			(layer "B.CrtYd")
		)
		(fp_rect
			(start 0.4318 0.9525)
			(end -0.4318 -0.9525)
			(stroke
				(width 0)
				(type default)
			)
			(fill no)
			(layer "B.Fab")
		)
		(pad "1" smd custom
			(at 0 -0.4445 90)
			(size 0.1524 0.1524)
			(layers "B.Cu" "B.Mask" "B.Paste")
			(net "VR_PVDDQ_DEF_AIREF1")
			(options
				(clearance outline)
				(anchor circle)
			)
			(primitives
				(gr_poly
					(pts
						(arc
							(start 0.3048 0.2032)
							(mid 0.275042 0.275042)
							(end 0.2032 0.3048)
						)
						(arc
							(start -0.2032 0.3048)
							(mid -0.275042 0.275042)
							(end -0.3048 0.2032)
						)
						(arc
							(start -0.3048 -0.2032)
							(mid -0.275042 -0.275042)
							(end -0.2032 -0.3048)
						)
						(arc
							(start 0.2032 -0.3048)
							(mid 0.275042 -0.275042)
							(end 0.3048 -0.2032)
						)
					)
					(width 0)
					(fill yes)
				)
			)
		)
		(pad "2" smd custom
			(at 0 0.4445 90)
			(size 0.1524 0.1524)
			(layers "B.Cu" "B.Mask" "B.Paste")
			(net "ISENSE_PVDDQ_DEF_PH1_IMON")
			(options
				(clearance outline)
				(anchor circle)
			)
			(primitives
				(gr_poly
					(pts
						(arc
							(start 0.3048 0.2032)
							(mid 0.275042 0.275042)
							(end 0.2032 0.3048)
						)
						(arc
							(start -0.2032 0.3048)
							(mid -0.275042 0.275042)
							(end -0.3048 0.2032)
						)
						(arc
							(start -0.3048 -0.2032)
							(mid -0.275042 -0.275042)
							(end -0.2032 -0.3048)
						)
						(arc
							(start 0.2032 -0.3048)
							(mid 0.275042 -0.275042)
							(end 0.3048 -0.2032)
						)
					)
					(width 0)
					(fill yes)
				)
			)
		)
	)
	(footprint ""
		(layer "B.Cu")
		(at 491.9345 -40.0304 -90)
		(property "Reference" "R1T1"
			(at 0 0 90)
			(layer "B.SilkS")
			(hide yes)
			(effects
				(font
					(size 1.27 1.27)
				)
				(justify mirror)
			)
		)
		(property "Value" ""
			(at 0 0 90)
			(layer "B.Fab")
			(effects
				(font
					(size 1.27 1.27)
				)
				(justify mirror)
			)
		)
		(duplicate_pad_numbers_are_jumpers no)
		(fp_poly
			(pts
				(xy 0.2794 -0.1016) (xy -0.2794 -0.1016) (xy -0.2794 0.9906) (xy 0.2794 0.9906)
			)
			(stroke
				(width 0)
				(type default)
			)
			(fill no)
			(layer "B.CrtYd")
		)
		(fp_line
			(start -0.2794 0.9906)
			(end -0.2794 -0.1016)
			(stroke
				(width 0.1)
				(type default)
			)
			(layer "B.Fab")
		)
		(fp_line
			(start 0.2794 0.9906)
			(end -0.2794 0.9906)
			(stroke
				(width 0.1)
				(type default)
			)
			(layer "B.Fab")
		)
		(fp_line
			(start -0.2794 -0.1016)
			(end 0.2794 -0.1016)
			(stroke
				(width 0.1)
				(type default)
			)
			(layer "B.Fab")
		)
		(fp_line
			(start 0.2794 -0.1016)
			(end 0.2794 0.9906)
			(stroke
				(width 0.1)
				(type default)
			)
			(layer "B.Fab")
		)
		(pad "1" smd rect
			(at 0 0 90)
			(size 0.508 0.508)
			(layers "B.Cu" "B.Mask" "B.Paste")
			(net "RMII_BMC_PCH_SPRNGVLLE_CRSDV")
		)
		(pad "2" smd rect
			(at 0 0.889 90)
			(size 0.508 0.508)
			(layers "B.Cu" "B.Mask" "B.Paste")
			(net "GND")
		)
		(zone
			(layer "B.Cu")
			(hatch none 0.5)
			(connect_pads
				(clearance 0)
			)
			(min_thickness 0.25)
			(keepout
				(tracks not_allowed)
				(vias allowed)
				(pads allowed)
				(copperpour not_allowed)
				(footprints allowed)
			)
			(placement
				(enabled no)
				(sheetname "")
			)
			(fill
				(thermal_gap 0.5)
				(thermal_bridge_width 0.5)
				(island_removal_mode 0)
			)
			(polygon
				(pts
					(xy 491.2995 -39.7764) (xy 491.2995 -40.2844) (xy 491.6805 -40.2844) (xy 491.6805 -39.7764)
				)
			)
		)
		(zone
			(layer "B.Cu")
			(hatch none 0.5)
			(connect_pads
				(clearance 0)
			)
			(min_thickness 0.25)
			(keepout
				(tracks allowed)
				(vias not_allowed)
				(pads allowed)
				(copperpour not_allowed)
				(footprints allowed)
			)
			(placement
				(enabled no)
				(sheetname "")
			)
			(fill
				(thermal_gap 0.5)
				(thermal_bridge_width 0.5)
				(island_removal_mode 0)
			)
			(polygon
				(pts
					(xy 491.6805 -39.7764) (xy 491.6805 -40.2844) (xy 491.2995 -40.2844) (xy 491.2995 -39.7764)
				)
			)
		)
	)
	(footprint ""
		(layer "B.Cu")
		(at 331.0255 -61.341 -90)
		(property "Reference" "R3P60"
			(at 0 0 90)
			(layer "B.SilkS")
			(hide yes)
			(effects
				(font
					(size 1.27 1.27)
				)
				(justify mirror)
			)
		)
		(property "Value" ""
			(at 0 0 90)
			(layer "B.Fab")
			(effects
				(font
					(size 1.27 1.27)
				)
				(justify mirror)
			)
		)
		(duplicate_pad_numbers_are_jumpers no)
		(fp_poly
			(pts
				(xy 0.2794 -0.1016) (xy -0.2794 -0.1016) (xy -0.2794 0.9906) (xy 0.2794 0.9906)
			)
			(stroke
				(width 0)
				(type default)
			)
			(fill no)
			(layer "B.CrtYd")
		)
		(fp_line
			(start -0.2794 0.9906)
			(end -0.2794 -0.1016)
			(stroke
				(width 0.1)
				(type default)
			)
			(layer "B.Fab")
		)
		(fp_line
			(start 0.2794 0.9906)
			(end -0.2794 0.9906)
			(stroke
				(width 0.1)
				(type default)
			)
			(layer "B.Fab")
		)
		(fp_line
			(start -0.2794 -0.1016)
			(end 0.2794 -0.1016)
			(stroke
				(width 0.1)
				(type default)
			)
			(layer "B.Fab")
		)
		(fp_line
			(start 0.2794 -0.1016)
			(end 0.2794 0.9906)
			(stroke
				(width 0.1)
				(type default)
			)
			(layer "B.Fab")
		)
		(pad "1" smd rect
			(at 0 0 90)
			(size 0.508 0.508)
			(layers "B.Cu" "B.Mask" "B.Paste")
			(net "PVCCIO_CPU0")
		)
		(pad "2" smd rect
			(at 0 0.889 90)
			(size 0.508 0.508)
			(layers "B.Cu" "B.Mask" "B.Paste")
			(net "SMB_DDR_DEF_SCL_G")
		)
		(zone
			(layer "B.Cu")
			(hatch none 0.5)
			(connect_pads
				(clearance 0)
			)
			(min_thickness 0.25)
			(keepout
				(tracks not_allowed)
				(vias allowed)
				(pads allowed)
				(copperpour not_allowed)
				(footprints allowed)
			)
			(placement
				(enabled no)
				(sheetname "")
			)
			(fill
				(thermal_gap 0.5)
				(thermal_bridge_width 0.5)
				(island_removal_mode 0)
			)
			(polygon
				(pts
					(xy 330.3905 -61.087) (xy 330.3905 -61.595) (xy 330.7715 -61.595) (xy 330.7715 -61.087)
				)
			)
		)
		(zone
			(layer "B.Cu")
			(hatch none 0.5)
			(connect_pads
				(clearance 0)
			)
			(min_thickness 0.25)
			(keepout
				(tracks allowed)
				(vias not_allowed)
				(pads allowed)
				(copperpour not_allowed)
				(footprints allowed)
			)
			(placement
				(enabled no)
				(sheetname "")
			)
			(fill
				(thermal_gap 0.5)
				(thermal_bridge_width 0.5)
				(island_removal_mode 0)
			)
			(polygon
				(pts
					(xy 330.7715 -61.087) (xy 330.7715 -61.595) (xy 330.3905 -61.595) (xy 330.3905 -61.087)
				)
			)
		)
	)
)
